(kicad_pcb
	(version 20260206)
	(generator "pcbnew")
	(generator_version "10.0")
	(general
		(thickness 1.6)
		(legacy_teardrops no)
	)
	(paper "A4")
	(title_block
		(title "peb — Lightning_PEB_BRD.brd")
		(comment 1 "Lightning (Wiwynn / Facebook NVMe JBOF) / footprints 57-64 of 2563")
	)
	(layers
		(0 "F.Cu" signal "TOP")
		(4 "In1.Cu" signal "L2GND")
		(6 "In2.Cu" signal "L3")
		(8 "In3.Cu" signal "L4VCC")
		(10 "In4.Cu" signal "L5VCC")
		(12 "In5.Cu" signal "L6")
		(14 "In6.Cu" signal "L7GND")
		(2 "B.Cu" signal "BOTTOM")
		(9 "F.Adhes" user "F.Adhesive")
		(11 "B.Adhes" user "B.Adhesive")
		(13 "F.Paste" user "Package Geometry/Pastemask Top")
		(15 "B.Paste" user "Package Geometry/Pastemask Bottom")
		(5 "F.SilkS" user "Ref Des/Silkscreen Top")
		(7 "B.SilkS" user "Ref Des/Silkscreen Bottom")
		(1 "F.Mask" user "Board Geometry/Soldermask Top")
		(3 "B.Mask" user "Board Geometry/Soldermask Bottom")
		(17 "Dwgs.User" user "User.Drawings")
		(19 "Cmts.User" user "User.Comments")
		(21 "Eco1.User" user "User.Eco1")
		(23 "Eco2.User" user "User.Eco2")
		(25 "Edge.Cuts" user "Board Geometry/Outline")
		(27 "Margin" user)
		(31 "F.CrtYd" user "Package Geometry/Place Bound Top")
		(29 "B.CrtYd" user "Package Geometry/Place Bound Bottom")
		(35 "F.Fab" user "Ref Des/Assembly Top")
		(33 "B.Fab" user "Ref Des/Assembly Bottom")
	)
	(footprint ""
		(layer "F.Cu")
		(at 273.939 -12.7 90)
		(property "Reference" "C1"
			(at 0 0 90)
			(layer "F.SilkS")
			(hide yes)
			(effects
				(font
					(size 1.27 1.27)
				)
			)
		)
		(property "Value" "SCD22U10V2KX-1GP"
			(at 1.1811 -2.7051 90)
			(unlocked yes)
			(layer "F.Fab")
			(hide yes)
			(effects
				(font
					(size 1.016 1.016)
					(thickness 0.1524)
				)
			)
		)
		(property "Device Type" "C402H22"
			(at 1.1811 -4.2291 90)
			(unlocked yes)
			(layer "F.Fab")
			(hide yes)
			(effects
				(font
					(size 1.016 1.016)
					(thickness 0.1524)
				)
			)
		)
		(duplicate_pad_numbers_are_jumpers no)
		(fp_rect
			(start -0.4318 0.9525)
			(end 0.4318 -0.9525)
			(stroke
				(width 0)
				(type default)
			)
			(fill no)
			(layer "F.CrtYd")
		)
		(fp_rect
			(start -0.4318 0.9525)
			(end 0.4318 -0.9525)
			(stroke
				(width 0)
				(type default)
			)
			(fill no)
			(layer "F.Fab")
		)
		(pad "1" smd custom
			(at 0 -0.4445 90)
			(size 0.1524 0.1524)
			(layers "F.Cu" "F.Mask" "F.Paste")
			(net "PCIE_TX_CAP_N0")
			(options
				(clearance outline)
				(anchor circle)
			)
			(primitives
				(gr_poly
					(pts
						(arc
							(start 0.3048 -0.2032)
							(mid 0.275042 -0.275042)
							(end 0.2032 -0.3048)
						)
						(arc
							(start -0.2032 -0.3048)
							(mid -0.275042 -0.275042)
							(end -0.3048 -0.2032)
						)
						(arc
							(start -0.3048 0.2032)
							(mid -0.275042 0.275042)
							(end -0.2032 0.3048)
						)
						(arc
							(start 0.2032 0.3048)
							(mid 0.275042 0.275042)
							(end 0.3048 0.2032)
						)
					)
					(width 0)
					(fill yes)
				)
			)
		)
		(pad "2" smd custom
			(at 0 0.4445 90)
			(size 0.1524 0.1524)
			(layers "F.Cu" "F.Mask" "F.Paste")
			(net "PCIE_TX_N0")
			(options
				(clearance outline)
				(anchor circle)
			)
			(primitives
				(gr_poly
					(pts
						(arc
							(start 0.3048 -0.2032)
							(mid 0.275042 -0.275042)
							(end 0.2032 -0.3048)
						)
						(arc
							(start -0.2032 -0.3048)
							(mid -0.275042 -0.275042)
							(end -0.3048 -0.2032)
						)
						(arc
							(start -0.3048 0.2032)
							(mid -0.275042 0.275042)
							(end -0.2032 0.3048)
						)
						(arc
							(start 0.2032 0.3048)
							(mid 0.275042 0.275042)
							(end 0.3048 0.2032)
						)
					)
					(width 0)
					(fill yes)
				)
			)
		)
	)
	(footprint ""
		(layer "F.Cu")
		(at 236.3724 -19.9644 -90)
		(property "Reference" "SR720"
			(at 0 0 270)
			(layer "F.SilkS")
			(hide yes)
			(effects
				(font
					(size 1.27 1.27)
				)
			)
		)
		(property "Value" "150R2F-1-GP"
			(at 0.064008 -3.993896 270)
			(unlocked yes)
			(layer "F.Fab")
			(hide yes)
			(effects
				(font
					(size 1.016 1.016)
					(thickness 0.1524)
				)
			)
		)
		(property "Device Type" "R402H16"
			(at 0.064008 -5.517896 270)
			(unlocked yes)
			(layer "F.Fab")
			(hide yes)
			(effects
				(font
					(size 1.016 1.016)
					(thickness 0.1524)
				)
			)
		)
		(duplicate_pad_numbers_are_jumpers no)
		(fp_line
			(start -0.508 -0.9398)
			(end -0.508 0.9398)
			(stroke
				(width 0.1524)
				(type default)
			)
			(layer "F.SilkS")
		)
		(fp_line
			(start 0.508 -0.9398)
			(end -0.508 -0.9398)
			(stroke
				(width 0.1524)
				(type default)
			)
			(layer "F.SilkS")
		)
		(fp_rect
			(start -0.508 0.9398)
			(end 0.508 -0.9398)
			(stroke
				(width 0)
				(type default)
			)
			(fill no)
			(layer "F.CrtYd")
		)
		(fp_rect
			(start -0.508 0.9398)
			(end 0.508 -0.9398)
			(stroke
				(width 0)
				(type default)
			)
			(fill no)
			(layer "F.Fab")
		)
		(pad "1" smd custom
			(at 0 -0.4445 270)
			(size 0.1397 0.1397)
			(layers "F.Cu" "F.Mask" "F.Paste")
			(net "P3V3_STBY")
			(options
				(clearance outline)
				(anchor circle)
			)
			(primitives
				(gr_poly
					(pts
						(arc
							(start -0.1778 -0.2794)
							(mid -0.249642 -0.249642)
							(end -0.2794 -0.1778)
						)
						(arc
							(start -0.2794 0.1778)
							(mid -0.249642 0.249642)
							(end -0.1778 0.2794)
						)
						(arc
							(start 0.1778 0.2794)
							(mid 0.249642 0.249642)
							(end 0.2794 0.1778)
						)
						(arc
							(start 0.2794 -0.1778)
							(mid 0.249642 -0.249642)
							(end 0.1778 -0.2794)
						)
					)
					(width 0)
					(fill yes)
				)
			)
		)
		(pad "2" smd custom
			(at 0 0.4445 270)
			(size 0.1397 0.1397)
			(layers "F.Cu" "F.Mask" "F.Paste")
			(net "SLED29_A")
			(options
				(clearance outline)
				(anchor circle)
			)
			(primitives
				(gr_poly
					(pts
						(arc
							(start -0.1778 -0.2794)
							(mid -0.249642 -0.249642)
							(end -0.2794 -0.1778)
						)
						(arc
							(start -0.2794 0.1778)
							(mid -0.249642 0.249642)
							(end -0.1778 0.2794)
						)
						(arc
							(start 0.1778 0.2794)
							(mid 0.249642 0.249642)
							(end 0.2794 0.1778)
						)
						(arc
							(start 0.2794 -0.1778)
							(mid 0.249642 -0.249642)
							(end 0.1778 -0.2794)
						)
					)
					(width 0)
					(fill yes)
				)
			)
		)
	)
	(footprint ""
		(layer "F.Cu")
		(at 191.408304 -212.420454 180)
		(property "Reference" "C122"
			(at 0 0 180)
			(layer "F.SilkS")
			(hide yes)
			(effects
				(font
					(size 1.27 1.27)
				)
			)
		)
		(property "Value" "SCD22U10V2KX-1GP"
			(at 1.1811 -2.7051 180)
			(unlocked yes)
			(layer "F.Fab")
			(hide yes)
			(effects
				(font
					(size 1.016 1.016)
					(thickness 0.1524)
				)
			)
		)
		(property "Device Type" "C402H22"
			(at 1.1811 -4.2291 180)
			(unlocked yes)
			(layer "F.Fab")
			(hide yes)
			(effects
				(font
					(size 1.016 1.016)
					(thickness 0.1524)
				)
			)
		)
		(duplicate_pad_numbers_are_jumpers no)
		(fp_rect
			(start -0.4318 0.9525)
			(end 0.4318 -0.9525)
			(stroke
				(width 0)
				(type default)
			)
			(fill no)
			(layer "F.CrtYd")
		)
		(fp_rect
			(start -0.4318 0.9525)
			(end 0.4318 -0.9525)
			(stroke
				(width 0)
				(type default)
			)
			(fill no)
			(layer "F.Fab")
		)
		(pad "1" smd custom
			(at 0 -0.4445 180)
			(size 0.1524 0.1524)
			(layers "F.Cu" "F.Mask" "F.Paste")
			(net "PCIE_TX_CAP_N45")
			(options
				(clearance outline)
				(anchor circle)
			)
			(primitives
				(gr_poly
					(pts
						(arc
							(start 0.3048 -0.2032)
							(mid 0.275042 -0.275042)
							(end 0.2032 -0.3048)
						)
						(arc
							(start -0.2032 -0.3048)
							(mid -0.275042 -0.275042)
							(end -0.3048 -0.2032)
						)
						(arc
							(start -0.3048 0.2032)
							(mid -0.275042 0.275042)
							(end -0.2032 0.3048)
						)
						(arc
							(start 0.2032 0.3048)
							(mid 0.275042 0.275042)
							(end 0.3048 0.2032)
						)
					)
					(width 0)
					(fill yes)
				)
			)
		)
		(pad "2" smd custom
			(at 0 0.4445 180)
			(size 0.1524 0.1524)
			(layers "F.Cu" "F.Mask" "F.Paste")
			(net "PCIE_TX_N45")
			(options
				(clearance outline)
				(anchor circle)
			)
			(primitives
				(gr_poly
					(pts
						(arc
							(start 0.3048 -0.2032)
							(mid 0.275042 -0.275042)
							(end 0.2032 -0.3048)
						)
						(arc
							(start -0.2032 -0.3048)
							(mid -0.275042 -0.275042)
							(end -0.3048 -0.2032)
						)
						(arc
							(start -0.3048 0.2032)
							(mid -0.275042 0.275042)
							(end -0.2032 0.3048)
						)
						(arc
							(start 0.2032 0.3048)
							(mid 0.275042 0.275042)
							(end 0.3048 0.2032)
						)
					)
					(width 0)
					(fill yes)
				)
			)
		)
	)
	(footprint ""
		(layer "F.Cu")
		(at 178.1048 -63.881 180)
		(property "Reference" "PG21"
			(at 0 0 180)
			(layer "F.SilkS")
			(hide yes)
			(effects
				(font
					(size 1.27 1.27)
				)
			)
		)
		(property "Value" "GAP-CLOSE-PWR-3-GP"
			(at 0.0254 -6.5786 180)
			(unlocked yes)
			(layer "F.Fab")
			(hide yes)
			(effects
				(font
					(size 1.016 1.016)
					(thickness 0.1524)
				)
			)
		)
		(property "Device Type" "GAP-CLOSE-PWR-3"
			(at 0.0254 -8.255 180)
			(unlocked yes)
			(layer "F.Fab")
			(hide yes)
			(effects
				(font
					(size 1.016 1.016)
					(thickness 0.1524)
				)
			)
		)
		(duplicate_pad_numbers_are_jumpers no)
		(fp_rect
			(start -0.7112 0.4572)
			(end 0.7112 -0.4572)
			(stroke
				(width 0)
				(type default)
			)
			(fill no)
			(layer "F.CrtYd")
		)
		(fp_poly
			(pts
				(xy -0.7112 -0.4572) (xy 0.7112 -0.4572) (xy 0.7112 0.4572) (xy -0.7112 0.4572)
			)
			(stroke
				(width 0)
				(type default)
			)
			(fill no)
			(layer "F.Fab")
		)
		(pad "1" smd rect
			(at -0.3048 0 180)
			(size 0.6604 0.762)
			(layers "F.Cu" "F.Mask" "F.Paste")
			(net "DUT_AVD_PCIE")
		)
		(pad "2" smd rect
			(at 0.3048 0 180)
			(size 0.6604 0.762)
			(layers "F.Cu" "F.Mask" "F.Paste")
			(net "P0V9")
		)
	)
	(footprint ""
		(layer "F.Cu")
		(at 228.195124 -203.047092 180)
		(property "Reference" "R7932"
			(at 0 0 180)
			(layer "F.SilkS")
			(hide yes)
			(effects
				(font
					(size 1.27 1.27)
				)
			)
		)
		(property "Value" "0R2J-2-GP"
			(at 0.064008 -3.993896 180)
			(unlocked yes)
			(layer "F.Fab")
			(hide yes)
			(effects
				(font
					(size 1.016 1.016)
					(thickness 0.1524)
				)
			)
		)
		(property "Device Type" "R402H16"
			(at 0.064008 -5.517896 180)
			(unlocked yes)
			(layer "F.Fab")
			(hide yes)
			(effects
				(font
					(size 1.016 1.016)
					(thickness 0.1524)
				)
			)
		)
		(duplicate_pad_numbers_are_jumpers no)
		(fp_line
			(start 0.508 -0.9398)
			(end -0.508 -0.9398)
			(stroke
				(width 0.1524)
				(type default)
			)
			(layer "F.SilkS")
		)
		(fp_line
			(start -0.508 -0.9398)
			(end -0.508 0.9398)
			(stroke
				(width 0.1524)
				(type default)
			)
			(layer "F.SilkS")
		)
		(fp_rect
			(start -0.508 0.9398)
			(end 0.508 -0.9398)
			(stroke
				(width 0)
				(type default)
			)
			(fill no)
			(layer "F.CrtYd")
		)
		(fp_rect
			(start -0.508 0.9398)
			(end 0.508 -0.9398)
			(stroke
				(width 0)
				(type default)
			)
			(fill no)
			(layer "F.Fab")
		)
		(pad "1" smd custom
			(at 0 -0.4445 180)
			(size 0.1397 0.1397)
			(layers "F.Cu" "F.Mask" "F.Paste")
			(net "SSD_PRSNT#12")
			(options
				(clearance outline)
				(anchor circle)
			)
			(primitives
				(gr_poly
					(pts
						(arc
							(start -0.1778 -0.2794)
							(mid -0.249642 -0.249642)
							(end -0.2794 -0.1778)
						)
						(arc
							(start -0.2794 0.1778)
							(mid -0.249642 0.249642)
							(end -0.1778 0.2794)
						)
						(arc
							(start 0.1778 0.2794)
							(mid 0.249642 0.249642)
							(end 0.2794 0.1778)
						)
						(arc
							(start 0.2794 -0.1778)
							(mid 0.249642 -0.249642)
							(end 0.1778 -0.2794)
						)
					)
					(width 0)
					(fill yes)
				)
			)
		)
		(pad "2" smd custom
			(at 0 0.4445 180)
			(size 0.1397 0.1397)
			(layers "F.Cu" "F.Mask" "F.Paste")
			(net "SSD_PRSNT#12_R")
			(options
				(clearance outline)
				(anchor circle)
			)
			(primitives
				(gr_poly
					(pts
						(arc
							(start -0.1778 -0.2794)
							(mid -0.249642 -0.249642)
							(end -0.2794 -0.1778)
						)
						(arc
							(start -0.2794 0.1778)
							(mid -0.249642 0.249642)
							(end -0.1778 0.2794)
						)
						(arc
							(start 0.1778 0.2794)
							(mid 0.249642 0.249642)
							(end 0.2794 0.1778)
						)
						(arc
							(start 0.2794 -0.1778)
							(mid 0.249642 -0.249642)
							(end 0.1778 -0.2794)
						)
					)
					(width 0)
					(fill yes)
				)
			)
		)
	)
	(footprint ""
		(layer "F.Cu")
		(at 80.428084 -74.99985)
		(property "Reference" "R732"
			(at 0 0 0)
			(layer "F.SilkS")
			(hide yes)
			(effects
				(font
					(size 1.27 1.27)
				)
			)
		)
		(property "Value" "0R2J-2-GP"
			(at 0.064008 -3.993896 0)
			(unlocked yes)
			(layer "F.Fab")
			(hide yes)
			(effects
				(font
					(size 1.016 1.016)
					(thickness 0.1524)
				)
			)
		)
		(property "Device Type" "R402H16"
			(at 0.064008 -5.517896 0)
			(unlocked yes)
			(layer "F.Fab")
			(hide yes)
			(effects
				(font
					(size 1.016 1.016)
					(thickness 0.1524)
				)
			)
		)
		(duplicate_pad_numbers_are_jumpers no)
		(fp_line
			(start -0.508 -0.9398)
			(end -0.508 0.9398)
			(stroke
				(width 0.1524)
				(type default)
			)
			(layer "F.SilkS")
		)
		(fp_line
			(start 0.508 -0.9398)
			(end -0.508 -0.9398)
			(stroke
				(width 0.1524)
				(type default)
			)
			(layer "F.SilkS")
		)
		(fp_rect
			(start -0.508 0.9398)
			(end 0.508 -0.9398)
			(stroke
				(width 0)
				(type default)
			)
			(fill no)
			(layer "F.CrtYd")
		)
		(fp_rect
			(start -0.508 0.9398)
			(end 0.508 -0.9398)
			(stroke
				(width 0)
				(type default)
			)
			(fill no)
			(layer "F.Fab")
		)
		(pad "1" smd custom
			(at 0 -0.4445)
			(size 0.1397 0.1397)
			(layers "F.Cu" "F.Mask" "F.Paste")
			(net "FM_BMC_RESET_N")
			(options
				(clearance outline)
				(anchor circle)
			)
			(primitives
				(gr_poly
					(pts
						(arc
							(start -0.1778 -0.2794)
							(mid -0.249642 -0.249642)
							(end -0.2794 -0.1778)
						)
						(arc
							(start -0.2794 0.1778)
							(mid -0.249642 0.249642)
							(end -0.1778 0.2794)
						)
						(arc
							(start 0.1778 0.2794)
							(mid 0.249642 0.249642)
							(end 0.2794 0.1778)
						)
						(arc
							(start 0.2794 -0.1778)
							(mid 0.249642 -0.249642)
							(end 0.1778 -0.2794)
						)
					)
					(width 0)
					(fill yes)
				)
			)
		)
		(pad "2" smd custom
			(at 0 0.4445)
			(size 0.1397 0.1397)
			(layers "F.Cu" "F.Mask" "F.Paste")
			(net "SEC_RST_N_R")
			(options
				(clearance outline)
				(anchor circle)
			)
			(primitives
				(gr_poly
					(pts
						(arc
							(start -0.1778 -0.2794)
							(mid -0.249642 -0.249642)
							(end -0.2794 -0.1778)
						)
						(arc
							(start -0.2794 0.1778)
							(mid -0.249642 0.249642)
							(end -0.1778 0.2794)
						)
						(arc
							(start 0.1778 0.2794)
							(mid 0.249642 0.249642)
							(end 0.2794 0.1778)
						)
						(arc
							(start 0.2794 -0.1778)
							(mid 0.249642 -0.249642)
							(end 0.1778 -0.2794)
						)
					)
					(width 0)
					(fill yes)
				)
			)
		)
	)
	(footprint ""
		(layer "F.Cu")
		(at 39.5478 -103.632 180)
		(property "Reference" "R658"
			(at 0 0 180)
			(layer "F.SilkS")
			(hide yes)
			(effects
				(font
					(size 1.27 1.27)
				)
			)
		)
		(property "Value" "4K7R2F-GP"
			(at 0.064008 -3.993896 180)
			(unlocked yes)
			(layer "F.Fab")
			(hide yes)
			(effects
				(font
					(size 1.016 1.016)
					(thickness 0.1524)
				)
			)
		)
		(property "Device Type" "R402H16"
			(at 0.064008 -5.517896 180)
			(unlocked yes)
			(layer "F.Fab")
			(hide yes)
			(effects
				(font
					(size 1.016 1.016)
					(thickness 0.1524)
				)
			)
		)
		(duplicate_pad_numbers_are_jumpers no)
		(fp_line
			(start 0.508 -0.9398)
			(end -0.508 -0.9398)
			(stroke
				(width 0.1524)
				(type default)
			)
			(layer "F.SilkS")
		)
		(fp_line
			(start -0.508 -0.9398)
			(end -0.508 0.9398)
			(stroke
				(width 0.1524)
				(type default)
			)
			(layer "F.SilkS")
		)
		(fp_rect
			(start -0.508 0.9398)
			(end 0.508 -0.9398)
			(stroke
				(width 0)
				(type default)
			)
			(fill no)
			(layer "F.CrtYd")
		)
		(fp_rect
			(start -0.508 0.9398)
			(end 0.508 -0.9398)
			(stroke
				(width 0)
				(type default)
			)
			(fill no)
			(layer "F.Fab")
		)
		(pad "1" smd custom
			(at 0 -0.4445 180)
			(size 0.1397 0.1397)
			(layers "F.Cu" "F.Mask" "F.Paste")
			(net "GND")
			(options
				(clearance outline)
				(anchor circle)
			)
			(primitives
				(gr_poly
					(pts
						(arc
							(start -0.1778 -0.2794)
							(mid -0.249642 -0.249642)
							(end -0.2794 -0.1778)
						)
						(arc
							(start -0.2794 0.1778)
							(mid -0.249642 0.249642)
							(end -0.1778 0.2794)
						)
						(arc
							(start 0.1778 0.2794)
							(mid 0.249642 0.249642)
							(end 0.2794 0.1778)
						)
						(arc
							(start 0.2794 -0.1778)
							(mid 0.249642 -0.249642)
							(end 0.1778 -0.2794)
						)
					)
					(width 0)
					(fill yes)
				)
			)
		)
		(pad "2" smd custom
			(at 0 0.4445 180)
			(size 0.1397 0.1397)
			(layers "F.Cu" "F.Mask" "F.Paste")
			(net "SPI_FLASH_SELECT")
			(options
				(clearance outline)
				(anchor circle)
			)
			(primitives
				(gr_poly
					(pts
						(arc
							(start -0.1778 -0.2794)
							(mid -0.249642 -0.249642)
							(end -0.2794 -0.1778)
						)
						(arc
							(start -0.2794 0.1778)
							(mid -0.249642 0.249642)
							(end -0.1778 0.2794)
						)
						(arc
							(start 0.1778 0.2794)
							(mid 0.249642 0.249642)
							(end 0.2794 0.1778)
						)
						(arc
							(start 0.2794 -0.1778)
							(mid 0.249642 -0.249642)
							(end 0.1778 -0.2794)
						)
					)
					(width 0)
					(fill yes)
				)
			)
		)
	)
	(footprint ""
		(layer "F.Cu")
		(at 157.826202 -55.272432 -90)
		(property "Reference" "PR168"
			(at 0 0 270)
			(layer "F.SilkS")
			(hide yes)
			(effects
				(font
					(size 1.27 1.27)
				)
			)
		)
		(property "Value" "4K53R2F-1-GP"
			(at 0.064008 -3.993896 270)
			(unlocked yes)
			(layer "F.Fab")
			(hide yes)
			(effects
				(font
					(size 1.016 1.016)
					(thickness 0.1524)
				)
			)
		)
		(property "Device Type" "R402H16"
			(at 0.064008 -5.517896 270)
			(unlocked yes)
			(layer "F.Fab")
			(hide yes)
			(effects
				(font
					(size 1.016 1.016)
					(thickness 0.1524)
				)
			)
		)
		(duplicate_pad_numbers_are_jumpers no)
		(fp_line
			(start -0.508 -0.9398)
			(end -0.508 0.9398)
			(stroke
				(width 0.1524)
				(type default)
			)
			(layer "F.SilkS")
		)
		(fp_line
			(start 0.508 -0.9398)
			(end -0.508 -0.9398)
			(stroke
				(width 0.1524)
				(type default)
			)
			(layer "F.SilkS")
		)
		(fp_rect
			(start -0.508 0.9398)
			(end 0.508 -0.9398)
			(stroke
				(width 0)
				(type default)
			)
			(fill no)
			(layer "F.CrtYd")
		)
		(fp_rect
			(start -0.508 0.9398)
			(end 0.508 -0.9398)
			(stroke
				(width 0)
				(type default)
			)
			(fill no)
			(layer "F.Fab")
		)
		(pad "1" smd custom
			(at 0 -0.4445 270)
			(size 0.1397 0.1397)
			(layers "F.Cu" "F.Mask" "F.Paste")
			(net "P0V9_VFB_R")
			(options
				(clearance outline)
				(anchor circle)
			)
			(primitives
				(gr_poly
					(pts
						(arc
							(start -0.1778 -0.2794)
							(mid -0.249642 -0.249642)
							(end -0.2794 -0.1778)
						)
						(arc
							(start -0.2794 0.1778)
							(mid -0.249642 0.249642)
							(end -0.1778 0.2794)
						)
						(arc
							(start 0.1778 0.2794)
							(mid 0.249642 0.249642)
							(end 0.2794 0.1778)
						)
						(arc
							(start 0.2794 -0.1778)
							(mid 0.249642 -0.249642)
							(end 0.1778 -0.2794)
						)
					)
					(width 0)
					(fill yes)
				)
			)
		)
		(pad "2" smd custom
			(at 0 0.4445 270)
			(size 0.1397 0.1397)
			(layers "F.Cu" "F.Mask" "F.Paste")
			(net "P0V9_VFB")
			(options
				(clearance outline)
				(anchor circle)
			)
			(primitives
				(gr_poly
					(pts
						(arc
							(start -0.1778 -0.2794)
							(mid -0.249642 -0.249642)
							(end -0.2794 -0.1778)
						)
						(arc
							(start -0.2794 0.1778)
							(mid -0.249642 0.249642)
							(end -0.1778 0.2794)
						)
						(arc
							(start 0.1778 0.2794)
							(mid 0.249642 0.249642)
							(end 0.2794 0.1778)
						)
						(arc
							(start 0.2794 -0.1778)
							(mid 0.249642 -0.249642)
							(end 0.1778 -0.2794)
						)
					)
					(width 0)
					(fill yes)
				)
			)
		)
	)
)
